# T6G (Grand Teton) — schematic netlist excerpt (pin names and nets, part order shuffled) for the footprints in the layout excerpt that follows; sources: Cadence DE-HDL packaged netlist, KiCad conversion of 04192023_DAF0TMB3IC0_F0TG_MB_C_brd_V02_OCP.brd

J26  SCONN288_DDR506112002KQ  IO  pkg DDR288S_1-1VXC  page 99
  VIN_BULK0  = P12V_MEM_CPU1
  RFU0  = NC
  VIN_MGMT  = P3V3_AUX
  HSCL  = I3C_SPD_DDRB_CPU1_SCL
  HSDA  = I3C_SPD_DDRB_CPU1_SDA
  VSS0  = GND
  DQ0_A  = M_B_CPU1_SA_DQ<0>
  VSS1  = GND
  DQ1_A  = M_B_CPU1_SA_DQ<1>
  VSS2  = GND
  DQS0_A_T  = M_B_CPU1_SA_DQS_DP<0>
  DQS0_A_C  = M_B_CPU1_SA_DQS_DN<0>
  VSS3  = GND
  DQ4_A  = M_B_CPU1_SA_DQ<4>
  VSS4  = GND
  DQ5_A  = M_B_CPU1_SA_DQ<5>
  VSS5  = GND
  DQ8_A  = M_B_CPU1_SA_DQ<8>
  VSS6  = GND
  DQ9_A  = M_B_CPU1_SA_DQ<9>
  VSS7  = GND
  DQS1_A_T  = M_B_CPU1_SA_DQS_DP<1>
  DQS1_A_C  = M_B_CPU1_SA_DQS_DN<1>
  VSS8  = GND
  DQ12_A  = M_B_CPU1_SA_DQ<12>
  VSS9  = GND
  DQ13_A  = M_B_CPU1_SA_DQ<13>
  VSS10  = GND
  DQ16_A  = M_B_CPU1_SA_DQ<16>
  VSS11  = GND
  DQ17_A  = M_B_CPU1_SA_DQ<17>
  VSS12  = GND
  DQS2_A_T  = M_B_CPU1_SA_DQS_DP<2>
  DQS2_A_C  = M_B_CPU1_SA_DQS_DN<2>
  VSS13  = GND
  DQ20_A  = M_B_CPU1_SA_DQ<20>
  VSS14  = GND
  DQ21_A  = M_B_CPU1_SA_DQ<21>
  VSS15  = GND
  DQ24_A  = M_B_CPU1_SA_DQ<24>
  VSS16  = GND
  DQ25_A  = M_B_CPU1_SA_DQ<25>
  VSS17  = GND
  DQS3_A_T  = M_B_CPU1_SA_DQS_DP<3>
  DQS3_A_C  = M_B_CPU1_SA_DQS_DN<3>
  VSS18  = GND
  DQ28_A  = M_B_CPU1_SA_DQ<28>
  VSS19  = GND
  DQ29_A  = M_B_CPU1_SA_DQ<29>
  VSS20  = GND
  CB0_A  = M_B_CPU1_SA_CB<0>
  VSS21  = GND
  CB1_A  = M_B_CPU1_SA_CB<1>
  VSS22  = GND
  DQS4_A_T  = M_B_CPU1_SA_DQS_DP<4>
  DQS4_A_C  = M_B_CPU1_SA_DQS_DN<4>
  VSS23  = GND
  CB4_A  = M_B_CPU1_SA_CB<4>
  VSS24  = GND
  CB5_A  = M_B_CPU1_SA_CB<5>
  VSS25  = GND
  ALERT_N  = M_B_CPU1_ALERT_N
  VSS26  = GND
  CS0_A_N  = M_B_CPU1_SA_CS_N<0>
  VSS27  = GND
  CA0_A  = M_B_CPU1_SA_CA<0>
  VSS28  = GND
  CA2_A  = M_B_CPU1_SA_CA<2>
  VSS29  = GND
  CA4_A  = M_B_CPU1_SA_CA<4>
  VSS30  = GND
  CA6_A  = M_B_CPU1_SA_CA<6>
  VSS31  = GND
  PAR_A  = M_B_CPU1_SA_PAR
  VSS32  = GND
  CA0_B  = M_B_CPU1_SB_CA<0>
  VSS33  = GND
  CA2_B  = M_B_CPU1_SB_CA<2>
  VSS34  = GND
  CA4_B  = M_B_CPU1_SB_CA<4>
  VSS35  = GND
  CA6_B  = M_B_CPU1_SB_CA<6>
  VSS36  = GND
  CS0_B_N  = M_B_CPU1_SB_CS_N<0>
  VSS37  = GND
  \lbd||rsp_a_n\  = M_B_CPU1_SA_RSP<0>
  \lbs||rsp_b_n\  = M_B_CPU1_SB_RSP<0>
  VSS38  = GND
  CB4_B  = M_B_CPU1_SB_CB<4>
  VSS39  = GND
  CB5_B  = M_B_CPU1_SB_CB<5>
  VSS40  = GND
  \dqs9_b_t||tdqs9_b_t||dbi4_b_n\  = M_B_CPU1_SB_DQS_DP<9>
  \dqs9_b_c||tdqs9_b_c\  = M_B_CPU1_SB_DQS_DN<9>
  VSS41  = GND
  CB0_B  = M_B_CPU1_SB_CB<0>
  VSS42  = GND
  CB1_B  = M_B_CPU1_SB_CB<1>
  VSS43  = GND
  DQ0_B  = M_B_CPU1_SB_DQ<0>
  VSS44  = GND
  DQ1_B  = M_B_CPU1_SB_DQ<1>
  VSS45  = GND
  DQS0_B_T  = M_B_CPU1_SB_DQS_DP<0>
  DQS0_B_C  = M_B_CPU1_SB_DQS_DN<0>
  VSS46  = GND
  DQ4_B  = M_B_CPU1_SB_DQ<4>
  VSS47  = GND
  DQ5_B  = M_B_CPU1_SB_DQ<5>
  VSS48  = GND
  DQ8_B  = M_B_CPU1_SB_DQ<8>
  VSS49  = GND
  DQ9_B  = M_B_CPU1_SB_DQ<9>
  VSS50  = GND
  DQS1_B_T  = M_B_CPU1_SB_DQS_DP<1>
  DQS1_B_C  = M_B_CPU1_SB_DQS_DN<1>
  VSS51  = GND
  DQ12_B  = M_B_CPU1_SB_DQ<12>
  VSS52  = GND
  DQ13_B  = M_B_CPU1_SB_DQ<13>
  VSS53  = GND
  DQ16_B  = M_B_CPU1_SB_DQ<16>
  VSS54  = GND
  DQ17_B  = M_B_CPU1_SB_DQ<17>
  VSS55  = GND
  DQS2_B_T  = M_B_CPU1_SB_DQS_DP<2>
  DQS2_B_C  = M_B_CPU1_SB_DQS_DN<2>
  VSS56  = GND
  DQ20_B  = M_B_CPU1_SB_DQ<20>
  VSS57  = GND
  DQ21_B  = M_B_CPU1_SB_DQ<21>
  VSS58  = GND
  DQ24_B  = M_B_CPU1_SB_DQ<24>
  VSS59  = GND
  DQ25_B  = M_B_CPU1_SB_DQ<25>
  VSS60  = GND
  DQS3_B_T  = M_B_CPU1_SB_DQS_DP<3>
  DQS3_B_C  = M_B_CPU1_SB_DQS_DN<3>
  VSS61  = GND
  DQ28_B  = M_B_CPU1_SB_DQ<28>
  VSS62  = GND
  DQ29_B  = M_B_CPU1_SB_DQ<29>
  VSS63  = GND
  RFU1  = NC
  VIN_BULK1  = P12V_MEM_CPU1
  VIN_BULK2  = P12V_MEM_CPU1
  \pwr_good||fail_n\  = PWRGD_CHB_CPU1_DIMM
  HAS  = PD_CHB_CPU1_DIMM_SAA
  RFU2  = NC
  RFU3  = NC
  VSS64  = GND
  DQ2_A  = M_B_CPU1_SA_DQ<2>
  VSS65  = GND
  DQ3_A  = M_B_CPU1_SA_DQ<3>
  VSS66  = GND
  \dqs5_a_c||tdqs5_a_c||dqs5_a_t||tdqs5_a_t\  = M_B_CPU1_SA_DQS_DN<5>
  \dqs5_a_t||tdqs5_a_t\  = M_B_CPU1_SA_DQS_DP<5>
  VSS67  = GND
  DQ6_A  = M_B_CPU1_SA_DQ<6>
  VSS68  = GND
  DQ7_A  = M_B_CPU1_SA_DQ<7>
  VSS69  = GND
  DQ10_A  = M_B_CPU1_SA_DQ<10>
  VSS70  = GND
  DQ11_A  = M_B_CPU1_SA_DQ<11>
  VSS71  = GND
  \dqs6_a_c||tdqs6_a_c||dqs6_a_t||tdqs6_a_t\  = M_B_CPU1_SA_DQS_DN<6>
  \dqs6_a_t||tdqs6_a_t\  = M_B_CPU1_SA_DQS_DP<6>
  VSS72  = GND
  DQ14_A  = M_B_CPU1_SA_DQ<14>
  VSS73  = GND
  DQ15_A  = M_B_CPU1_SA_DQ<15>
  VSS74  = GND
  DQ18_A  = M_B_CPU1_SA_DQ<18>
  VSS75  = GND
  DQ19_A  = M_B_CPU1_SA_DQ<19>
  VSS76  = GND
  \dqs7_a_c||tdqs7_a_c\  = M_B_CPU1_SA_DQS_DN<7>
  \dqs7_a_t||tdqs7_a_t\  = M_B_CPU1_SA_DQS_DP<7>
  VSS77  = GND
  DQ22_A  = M_B_CPU1_SA_DQ<22>
  VSS78  = GND
  DQ23_A  = M_B_CPU1_SA_DQ<23>
  VSS79  = GND
  DQ26_A  = M_B_CPU1_SA_DQ<26>
  VSS80  = GND
  DQ27_A  = M_B_CPU1_SA_DQ<27>
  VSS81  = GND
  \dqs8_a_c||tdqs8_a_c\  = M_B_CPU1_SA_DQS_DN<8>
  \dqs8_a_t||tdqs8_a_t\  = M_B_CPU1_SA_DQS_DP<8>
  VSS82  = GND
  DQ30_A  = M_B_CPU1_SA_DQ<30>
  VSS83  = GND
  DQ31_A  = M_B_CPU1_SA_DQ<31>
  VSS84  = GND
  CB2_A  = M_B_CPU1_SA_CB<2>
  VSS85  = GND
  CB3_A  = M_B_CPU1_SA_CB<3>
  VSS86  = GND
  \dqs9_a_c||tdqs9_a_c\  = M_B_CPU1_SA_DQS_DN<9>
  \dqs9_a_t||tdqs9_a_t\  = M_B_CPU1_SA_DQS_DP<9>
  VSS87  = GND
  CB6_A  = M_B_CPU1_SA_CB<6>
  VSS88  = GND
  CB7_A  = M_B_CPU1_SA_CB<7>
  VSS89  = GND
  RESET_N  = M_B_CPU1_RESET_N
  VSS90  = GND
  CS1_A_N  = M_B_CPU1_SA_CS_N<1>
  VSS91  = GND
  CA1_A  = M_B_CPU1_SA_CA<1>
  VSS92  = GND
  CA3_A  = M_B_CPU1_SA_CA<3>
  VSS93  = GND
  CA5_A  = M_B_CPU1_SA_CA<5>
  VSS94  = GND
  CK_T  = M_B_CPU1_CLK_DP<0>
  CK_C  = M_B_CPU1_CLK_DN<0>
  VSS95  = GND
  RFU4  = NC
  CA1_B  = M_B_CPU1_SB_CA<1>
  VSS96  = GND
  CA3_B  = M_B_CPU1_SB_CA<3>
  VSS97  = GND
  CA5_B  = M_B_CPU1_SB_CA<5>
  VSS98  = GND
  PAR_B  = M_B_CPU1_SB_PAR
  VSS99  = GND
  CS1_B_N  = M_B_CPU1_SB_CS_N<1>
  VSS100  = GND
  RFU5  = NC
  RFU6  = NC
  VSS101  = GND
  CB6_B  = M_B_CPU1_SB_CB<6>
  VSS102  = GND
  CB7_B  = M_B_CPU1_SB_CB<7>
  VSS103  = GND
  DQS4_B_C  = M_B_CPU1_SB_DQS_DN<4>
  DQS4_B_T  = M_B_CPU1_SB_DQS_DP<4>
  VSS104  = GND
  CB2_B  = M_B_CPU1_SB_CB<2>
  VSS105  = GND
  CB3_B  = M_B_CPU1_SB_CB<3>
  VSS106  = GND
  DQ2_B  = M_B_CPU1_SB_DQ<2>
  VSS107  = GND
  DQ3_B  = M_B_CPU1_SB_DQ<3>
  VSS108  = GND
  \dqs5_b_c||tdqs5_b_c\  = M_B_CPU1_SB_DQS_DN<5>
  \dqs5_b_t||tdqs5_b_t\  = M_B_CPU1_SB_DQS_DP<5>
  VSS109  = GND
  DQ6_B  = M_B_CPU1_SB_DQ<6>
  VSS110  = GND
  DQ7_B  = M_B_CPU1_SB_DQ<7>
  VSS111  = GND
  DQ10_B  = M_B_CPU1_SB_DQ<10>
  VSS112  = GND
  DQ11_B  = M_B_CPU1_SB_DQ<11>
  VSS113  = GND
  \dqs6_b_c||tdqs6_b_c\  = M_B_CPU1_SB_DQS_DN<6>
  \dqs6_b_t||tdqs6_b_t\  = M_B_CPU1_SB_DQS_DP<6>
  VSS114  = GND
  DQ14_B  = M_B_CPU1_SB_DQ<14>
  VSS115  = GND
  DQ15_B  = M_B_CPU1_SB_DQ<15>
  VSS116  = GND
  DQ18_B  = M_B_CPU1_SB_DQ<18>
  VSS117  = GND
  DQ19_B  = M_B_CPU1_SB_DQ<19>
  VSS118  = GND
  \dqs7_b_c||tdqs7_b_c\  = M_B_CPU1_SB_DQS_DN<7>
  \dqs7_b_t||tdqs7_b_t\  = M_B_CPU1_SB_DQS_DP<7>
  VSS119  = GND
  DQ22_B  = M_B_CPU1_SB_DQ<22>
  VSS120  = GND
  DQ23_B  = M_B_CPU1_SB_DQ<23>
  VSS121  = GND
  DQ26_B  = M_B_CPU1_SB_DQ<26>
  VSS122  = GND
  DQ27_B  = M_B_CPU1_SB_DQ<27>
  VSS123  = GND
  \dqs8_b_c||tdqs8_b_c\  = M_B_CPU1_SB_DQS_DN<8>
  \dqs8_b_t||tdqs8_b_t\  = M_B_CPU1_SB_DQS_DP<8>
  VSS124  = GND
  DQ30_B  = M_B_CPU1_SB_DQ<30>
  VSS125  = GND
  DQ31_B  = M_B_CPU1_SB_DQ<31>
  VSS126  = GND
  G1  = GND
  G2  = GND
  G3  = GND

(kicad_pcb
	(version 20260206)
	(generator "pcbnew")
	(generator_version "10.0")
	(general
		(thickness 1.6)
		(legacy_teardrops no)
	)
	(paper "A4")
	(title_block
		(title "04192023_DAF0TMB3IC0_F0TG_MB_C_brd_V02_OCP.brd")
		(comment 1 "Grand Teton / footprint 4371 of 8354 (J26), pads 231-276 of 291")
	)
	(layers
		(0 "F.Cu" signal "TOP")
		(4 "In1.Cu" signal "GND")
		(6 "In2.Cu" signal "IN1")
		(8 "In3.Cu" signal "GND1")
		(10 "In4.Cu" signal "IN2")
		(12 "In5.Cu" signal "GND2")
		(14 "In6.Cu" signal "IN3")
		(16 "In7.Cu" signal "GND3")
		(18 "In8.Cu" signal "VCC")
		(20 "In9.Cu" signal "VCC1")
		(22 "In10.Cu" signal "GND4")
		(24 "In11.Cu" signal "IN4")
		(26 "In12.Cu" signal "GND5")
		(28 "In13.Cu" signal "IN5")
		(30 "In14.Cu" signal "GND6")
		(32 "In15.Cu" signal "IN6")
		(34 "In16.Cu" signal "GND7")
		(2 "B.Cu" signal "BOTTOM")
		(9 "F.Adhes" user "F.Adhesive")
		(11 "B.Adhes" user "B.Adhesive")
		(13 "F.Paste" user "Package Geometry/Pastemask Top")
		(15 "B.Paste" user "Package Geometry/Pastemask Bottom")
		(5 "F.SilkS" user "Ref Des/Silkscreen Top")
		(7 "B.SilkS" user "Ref Des/Silkscreen Bottom")
		(1 "F.Mask" user "Board Geometry/Soldermask Top")
		(3 "B.Mask" user "Board Geometry/Soldermask Bottom")
		(17 "Dwgs.User" user "User.Drawings")
		(19 "Cmts.User" user "User.Comments")
		(21 "Eco1.User" user "User.Eco1")
		(23 "Eco2.User" user "User.Eco2")
		(25 "Edge.Cuts" user "Board Geometry/Outline")
		(27 "Margin" user)
		(31 "F.CrtYd" user "Package Geometry/Place Bound Top")
		(29 "B.CrtYd" user "Package Geometry/Place Bound Bottom")
		(35 "F.Fab" user "Ref Des/Assembly Top")
		(33 "B.Fab" user "Ref Des/Assembly Bottom")
	)
	(footprint ""
		(layer "F.Cu")
		(at 49.834038 -255.560322 180)
		(property "Reference" "J26"
			(at -0.703326 -82.357722 0)
			(unlocked yes)
			(layer "F.SilkS")
			(effects
				(font
					(size 0.7874 0.5842)
					(thickness 0.1524)
				)
			)
		)
		(property "Value" ""
			(at 0 0 180)
			(layer "F.Fab")
			(effects
				(font
					(size 1.27 1.27)
				)
			)
		)
		(duplicate_pad_numbers_are_jumpers no)
		(pad "231" smd rect
			(at 2.050034 14.875002 90)
			(size 0.519938 1.4986)
			(layers "F.Cu" "F.Mask" "F.Paste")
			(net "Net_2275")
		)
		(pad "232" smd rect
			(at 2.050034 15.724886 90)
			(size 0.519938 1.4986)
			(layers "F.Cu" "F.Mask" "F.Paste")
			(net "Net_2276")
		)
		(pad "233" smd rect
			(at 2.050034 16.575024 90)
			(size 0.519938 1.4986)
			(layers "F.Cu" "F.Mask" "F.Paste")
			(net "GND")
		)
		(pad "234" smd rect
			(at 2.050034 17.424908 90)
			(size 0.519938 1.4986)
			(layers "F.Cu" "F.Mask" "F.Paste")
			(net "M_B_CPU1_SB_CB<6>")
		)
		(pad "235" smd rect
			(at 2.050034 18.275046 90)
			(size 0.519938 1.4986)
			(layers "F.Cu" "F.Mask" "F.Paste")
			(net "GND")
		)
		(pad "236" smd rect
			(at 2.050034 19.12493 90)
			(size 0.519938 1.4986)
			(layers "F.Cu" "F.Mask" "F.Paste")
			(net "M_B_CPU1_SB_CB<7>")
		)
		(pad "237" smd rect
			(at 2.050034 19.975068 90)
			(size 0.519938 1.4986)
			(layers "F.Cu" "F.Mask" "F.Paste")
			(net "GND")
		)
		(pad "238" smd rect
			(at 2.050034 20.824952 90)
			(size 0.519938 1.4986)
			(layers "F.Cu" "F.Mask" "F.Paste")
			(net "M_B_CPU1_SB_DQS_DN<4>")
		)
		(pad "239" smd rect
			(at 2.050034 21.67509 90)
			(size 0.519938 1.4986)
			(layers "F.Cu" "F.Mask" "F.Paste")
			(net "M_B_CPU1_SB_DQS_DP<4>")
		)
		(pad "240" smd rect
			(at 2.050034 22.524974 90)
			(size 0.519938 1.4986)
			(layers "F.Cu" "F.Mask" "F.Paste")
			(net "GND")
		)
		(pad "241" smd rect
			(at 2.050034 23.375112 90)
			(size 0.519938 1.4986)
			(layers "F.Cu" "F.Mask" "F.Paste")
			(net "M_B_CPU1_SB_CB<2>")
		)
		(pad "242" smd rect
			(at 2.050034 24.224996 90)
			(size 0.519938 1.4986)
			(layers "F.Cu" "F.Mask" "F.Paste")
			(net "GND")
		)
		(pad "243" smd rect
			(at 2.050034 25.07488 90)
			(size 0.519938 1.4986)
			(layers "F.Cu" "F.Mask" "F.Paste")
			(net "M_B_CPU1_SB_CB<3>")
		)
		(pad "244" smd rect
			(at 2.050034 25.925018 90)
			(size 0.519938 1.4986)
			(layers "F.Cu" "F.Mask" "F.Paste")
			(net "GND")
		)
		(pad "245" smd rect
			(at 2.050034 26.774902 90)
			(size 0.519938 1.4986)
			(layers "F.Cu" "F.Mask" "F.Paste")
			(net "M_B_CPU1_SB_DQ<2>")
		)
		(pad "246" smd rect
			(at 2.050034 27.62504 90)
			(size 0.519938 1.4986)
			(layers "F.Cu" "F.Mask" "F.Paste")
			(net "GND")
		)
		(pad "247" smd rect
			(at 2.050034 28.474924 90)
			(size 0.519938 1.4986)
			(layers "F.Cu" "F.Mask" "F.Paste")
			(net "M_B_CPU1_SB_DQ<3>")
		)
		(pad "248" smd rect
			(at 2.050034 29.325062 90)
			(size 0.519938 1.4986)
			(layers "F.Cu" "F.Mask" "F.Paste")
			(net "GND")
		)
		(pad "249" smd rect
			(at 2.050034 30.174946 90)
			(size 0.519938 1.4986)
			(layers "F.Cu" "F.Mask" "F.Paste")
			(net "M_B_CPU1_SB_DQS_DN<5>")
		)
		(pad "250" smd rect
			(at 2.050034 31.025084 90)
			(size 0.519938 1.4986)
			(layers "F.Cu" "F.Mask" "F.Paste")
			(net "M_B_CPU1_SB_DQS_DP<5>")
		)
		(pad "251" smd rect
			(at 2.050034 31.874968 90)
			(size 0.519938 1.4986)
			(layers "F.Cu" "F.Mask" "F.Paste")
			(net "GND")
		)
		(pad "252" smd rect
			(at 2.050034 32.725106 90)
			(size 0.519938 1.4986)
			(layers "F.Cu" "F.Mask" "F.Paste")
			(net "M_B_CPU1_SB_DQ<6>")
		)
		(pad "253" smd rect
			(at 2.050034 33.57499 90)
			(size 0.519938 1.4986)
			(layers "F.Cu" "F.Mask" "F.Paste")
			(net "GND")
		)
		(pad "254" smd rect
			(at 2.050034 34.425128 90)
			(size 0.519938 1.4986)
			(layers "F.Cu" "F.Mask" "F.Paste")
			(net "M_B_CPU1_SB_DQ<7>")
		)
		(pad "255" smd rect
			(at 2.050034 35.275012 90)
			(size 0.519938 1.4986)
			(layers "F.Cu" "F.Mask" "F.Paste")
			(net "GND")
		)
		(pad "256" smd rect
			(at 2.050034 36.124896 90)
			(size 0.519938 1.4986)
			(layers "F.Cu" "F.Mask" "F.Paste")
			(net "M_B_CPU1_SB_DQ<10>")
		)
		(pad "257" smd rect
			(at 2.050034 36.975034 90)
			(size 0.519938 1.4986)
			(layers "F.Cu" "F.Mask" "F.Paste")
			(net "GND")
		)
		(pad "258" smd rect
			(at 2.050034 37.824918 90)
			(size 0.519938 1.4986)
			(layers "F.Cu" "F.Mask" "F.Paste")
			(net "M_B_CPU1_SB_DQ<11>")
		)
		(pad "259" smd rect
			(at 2.050034 38.675056 90)
			(size 0.519938 1.4986)
			(layers "F.Cu" "F.Mask" "F.Paste")
			(net "GND")
		)
		(pad "260" smd rect
			(at 2.050034 39.52494 90)
			(size 0.519938 1.4986)
			(layers "F.Cu" "F.Mask" "F.Paste")
			(net "M_B_CPU1_SB_DQS_DN<6>")
		)
		(pad "261" smd rect
			(at 2.050034 40.375078 90)
			(size 0.519938 1.4986)
			(layers "F.Cu" "F.Mask" "F.Paste")
			(net "M_B_CPU1_SB_DQS_DP<6>")
		)
		(pad "262" smd rect
			(at 2.050034 41.224962 90)
			(size 0.519938 1.4986)
			(layers "F.Cu" "F.Mask" "F.Paste")
			(net "GND")
		)
		(pad "263" smd rect
			(at 2.050034 42.0751 90)
			(size 0.519938 1.4986)
			(layers "F.Cu" "F.Mask" "F.Paste")
			(net "M_B_CPU1_SB_DQ<14>")
		)
		(pad "264" smd rect
			(at 2.050034 42.924984 90)
			(size 0.519938 1.4986)
			(layers "F.Cu" "F.Mask" "F.Paste")
			(net "GND")
		)
		(pad "265" smd rect
			(at 2.050034 43.775122 90)
			(size 0.519938 1.4986)
			(layers "F.Cu" "F.Mask" "F.Paste")
			(net "M_B_CPU1_SB_DQ<15>")
		)
		(pad "266" smd rect
			(at 2.050034 44.625006 90)
			(size 0.519938 1.4986)
			(layers "F.Cu" "F.Mask" "F.Paste")
			(net "GND")
		)
		(pad "267" smd rect
			(at 2.050034 45.47489 90)
			(size 0.519938 1.4986)
			(layers "F.Cu" "F.Mask" "F.Paste")
			(net "M_B_CPU1_SB_DQ<18>")
		)
		(pad "268" smd rect
			(at 2.050034 46.325028 90)
			(size 0.519938 1.4986)
			(layers "F.Cu" "F.Mask" "F.Paste")
			(net "GND")
		)
		(pad "269" smd rect
			(at 2.050034 47.174912 90)
			(size 0.519938 1.4986)
			(layers "F.Cu" "F.Mask" "F.Paste")
			(net "M_B_CPU1_SB_DQ<19>")
		)
		(pad "270" smd rect
			(at 2.050034 48.02505 90)
			(size 0.519938 1.4986)
			(layers "F.Cu" "F.Mask" "F.Paste")
			(net "GND")
		)
		(pad "271" smd rect
			(at 2.050034 48.874934 90)
			(size 0.519938 1.4986)
			(layers "F.Cu" "F.Mask" "F.Paste")
			(net "M_B_CPU1_SB_DQS_DN<7>")
		)
		(pad "272" smd rect
			(at 2.050034 49.725072 90)
			(size 0.519938 1.4986)
			(layers "F.Cu" "F.Mask" "F.Paste")
			(net "M_B_CPU1_SB_DQS_DP<7>")
		)
		(pad "273" smd rect
			(at 2.050034 50.574956 90)
			(size 0.519938 1.4986)
			(layers "F.Cu" "F.Mask" "F.Paste")
			(net "GND")
		)
		(pad "274" smd rect
			(at 2.050034 51.425094 90)
			(size 0.519938 1.4986)
			(layers "F.Cu" "F.Mask" "F.Paste")
			(net "M_B_CPU1_SB_DQ<22>")
		)
		(pad "275" smd rect
			(at 2.050034 52.274978 90)
			(size 0.519938 1.4986)
			(layers "F.Cu" "F.Mask" "F.Paste")
			(net "GND")
		)
		(pad "276" smd rect
			(at 2.050034 53.125116 90)
			(size 0.519938 1.4986)
			(layers "F.Cu" "F.Mask" "F.Paste")
			(net "M_B_CPU1_SB_DQ<23>")
		)
	)
)
